# S9S_MB_2U (Grand Teton) — schematic parts with pin connectivity, parts 3802–3949 of 6093; source: Cadence DE-HDL packaged netlist (pstxprt.dat, pstxnet.dat, pstchip.dat)

R962  Q_RES  33.2 1% CHIP  pkg 0402LF  page 235 : 1 = SMB_PEHPCPU1_GTL_SDA ; 2 = SMB_PEHPCPU1_GTL_R_SDA
R963  Q_RES  240 1% CHIP  pkg 0402LF  page 235 : 1 = PVNN_TERM_CPU1 ; 2 = SMB_PEHPCPU1_GTL_R_SCL
R964  Q_RES  240 1% CHIP  pkg 0402LF  page 235 : 1 = PVNN_TERM_CPU1 ; 2 = SMB_PEHPCPU1_GTL_R_SDA
R965  Q_RES  1K 1% CHIP  pkg 0402LF  page 235 : 1 = P3V3_AUX ; 2 = SMB_PEHPCPU0_LVC3_SCL
R966  Q_RES  1K 1% CHIP  pkg 0402LF  page 235 : 1 = P3V3_AUX ; 2 = SMB_PEHPCPU1_LVC3_SCL
R967  Q_RES  1K 1% CHIP  pkg 0402LF  page 235 : 1 = P3V3_AUX ; 2 = SMB_PEHPCPU0_LVC3_SDA
R968  Q_RES  1K 1% CHIP  pkg 0402LF  page 235 : 1 = P3V3_AUX ; 2 = SMB_PEHPCPU1_LVC3_SDA
R969  Q_RES  240 1% CHIP  pkg 0402LF  page 236 : 1 = PVNN_TERM_CPU0 ; 2 = SMB_S3M_CPU0_R_SCL
R970  Q_RES  240 1% CHIP  pkg 0402LF  page 236 : 1 = PVNN_TERM_CPU1 ; 2 = SMB_S3M_CPU1_R_SCL
R971  Q_RES  240 1% CHIP  pkg 0402LF  page 236 : 1 = PVNN_TERM_CPU0 ; 2 = SMB_S3M_CPU0_R_SDA
R972  Q_RES  240 1% CHIP  pkg 0402LF  page 236 : 1 = PVNN_TERM_CPU1 ; 2 = SMB_S3M_CPU1_R_SDA
R977  Q_RES  560 1% CHIP  pkg 0402LF  page 236 : 1 = P3V3_AUX ; 2 = SMB_S3M_CPU0_3V3AUX_SCL
R978  Q_RES  560 1% CHIP  pkg 0402LF  page 236 : 1 = P3V3_AUX ; 2 = SMB_S3M_CPU1_3V3AUX_SCL
R979  Q_RES  560 1% CHIP  pkg 0402LF  page 236 : 1 = P3V3_AUX ; 2 = SMB_S3M_CPU0_3V3AUX_SDA
R980  Q_RES  560 1% CHIP  pkg 0402LF  page 236 : 1 = P3V3_AUX ; 2 = SMB_S3M_CPU1_3V3AUX_SDA
R981  Q_RES  33.2 1% CHIP  pkg 0402LF  page 222 : 1 = FM_PVCCIN_CPU0_R_EN ; 2 = FM_PVCCIN_CPU0_EN
R982  Q_RES  33.2 1% CHIP  pkg 0402LF  page 222 : 1 = FM_PVCCFA_EHV_CPU0_R_EN ; 2 = FM_PVCCFA_EHV_CPU0_EN
R983  Q_RES  33.2 1% CHIP  pkg 0402LF  page 222 : 1 = FM_PVCCINFAON_CPU0_R_EN ; 2 = FM_PVCCINFAON_CPU0_EN
R984  Q_RES  33.2 1% CHIP  pkg 0402LF  page 222 : 1 = FM_PVCCFA_EHV_FIVRA_CPU0_R_EN ; 2 = FM_PVCCFA_EHV_FIVRA_CPU0_EN
R985  Q_RES  33.2 1% CHIP  pkg 0402LF  page 222 : 1 = FM_PVCCIN_CPU1_R_EN ; 2 = FM_PVCCIN_CPU1_EN
R986  Q_RES  33.2 1% CHIP  pkg 0402LF  page 222 : 1 = FM_PVCCFA_EHV_CPU1_R_EN ; 2 = FM_PVCCFA_EHV_CPU1_EN
R987  Q_RES  33.2 1% CHIP  pkg 0402LF  page 222 : 1 = FM_PVCCINFAON_CPU1_R_EN ; 2 = FM_PVCCINFAON_CPU1_EN
R988  Q_RES  33.2 1% CHIP  pkg 0402LF  page 222 : 1 = FM_PVCCFA_EHV_FIVRA_CPU1_R_EN ; 2 = FM_PVCCFA_EHV_FIVRA_CPU1_EN
R990  Q_RES  2K 1% CHIP  pkg 0402LF  page 219 : 1 = FM_PLD_CLK_25M_R_EN ; 2 = GND
R991  Q_RES  2K 1% CHIP  pkg 0402LF  page 219 : 1 = FM_AUX_SW_EN ; 2 = GND
R992  Q_RES  2K 1% EMPTY  pkg 0402LF  page 219 : 1 = PWRGD_CPU0_LVC1_R ; 2 = GND
R993  Q_RES  33.2 1% CHIP  pkg 0402LF  page 236 : 1 = SMB_S3M_CPU0_SCL ; 2 = SMB_S3M_CPU0_R_SCL
R994  Q_RES  33.2 1% CHIP  pkg 0402LF  page 236 : 1 = SMB_S3M_CPU0_SDA ; 2 = SMB_S3M_CPU0_R_SDA
R995  Q_RES  33.2 1% CHIP  pkg 0402LF  page 236 : 1 = SMB_S3M_CPU1_SCL ; 2 = SMB_S3M_CPU1_R_SCL
R996  Q_RES  33.2 1% CHIP  pkg 0402LF  page 236 : 1 = SMB_S3M_CPU1_SDA ; 2 = SMB_S3M_CPU1_R_SDA
R997  Q_RES  10K 1% EMPTY  pkg 0402LF  page 127 : 1 = PU_PIROM_CPU0_SM_WP ; 2 = GND
R998  Q_RES  0 5% CHIP  pkg 0402LF  page 235 : 1 = FM_SMB_PEHPCPU0_PCIE_ALERT_N ; 2 = FM_SMB_PEHPCPU0_PCIE_ALERT_R_N
R999  Q_RES  0 5% CHIP  pkg 0402LF  page 235 : 1 = FM_SMB_PEHPCPU1_PCIE_ALERT_N ; 2 = FM_SMB_PEHPCPU1_PCIE_ALERT_R_N
R1000  Q_RES  4.7K 5% CHIP  pkg 0402LF  page 235 : 1 = P3V3 ; 2 = FM_SMB_PEHPCPU0_PCIE_ALERT_R_N
R1001  Q_RES  4.7K 5% CHIP  pkg 0402LF  page 235 : 1 = P3V3 ; 2 = FM_SMB_PEHPCPU1_PCIE_ALERT_R_N
R1002  Q_RES  4.7K 5% CHIP  pkg 0402LF  page 235 : 1 = P3V3 ; 2 = FM_SMB_CPU0_ALERT_R1
R1003  Q_RES  4.7K 5% CHIP  pkg 0402LF  page 235 : 1 = P3V3 ; 2 = FM_SMB_CPU1_ALERT_R1
R1004  Q_RES  1K 1% CHIP  pkg 0402LF  page 127 : 1 = P3V3_AUX ; 2 = PU_PIROM_CPU1_SM_WP
R1005  Q_RES  10K 1% EMPTY  pkg 0402LF  page 127 : 1 = PU_PIROM_CPU1_SM_WP ; 2 = GND
R1006  Q_RES  4.7K 5% CHIP  pkg 0402LF  page 235 : 1 = PVNN_TERM_CPU0 ; 2 = FM_PEHPCPU0_ALERT_N
R1007  Q_RES  4.7K 5% CHIP  pkg 0402LF  page 235 : 1 = PVNN_TERM_CPU1 ; 2 = FM_PEHPCPU1_ALERT_N
R1008  Q_RES  1K 1% EMPTY  pkg 0402LF  page 119 : 1 = PVNN_TERM_CPU1 ; 2 = PU_TAP_ODT_CPU1_EN
R1009  Q_RES  1K 1% EMPTY  pkg 0402LF  page 119 : 1 = PVNN_TERM_CPU0 ; 2 = PU_TAP_ODT_CPU0_EN
R1010  Q_RES  0 5% CHIP  pkg 0402LF  page 209 : 1 = CLK_25M_CK440_ISCLK_REF_DP ; 2 = CLK_25M_PCH_REF_NS_DP
R1011  Q_RES  0 5% CHIP  pkg 0402LF  page 209 : 1 = CLK_25M_CK440_ISCLK_REF_DN ; 2 = CLK_25M_PCH_REF_NS_DN
R1012  Q_RES  0 5% CHIP  pkg 0402LF  page 209 : 1 = CLK_25M_CK440_CPU0_DP ; 2 = CLK_25M_CK440_CPU0_R_DP
R1013  Q_RES  0 5% EMPTY  pkg 0402LF  page 209 : 1 = CLK_25M_PCH_CPU0_DP ; 2 = CLK_25M_NSSC_CPU0_DP
R1014  Q_RES  0 5% CHIP  pkg 0402LF  page 209 : 1 = CLK_25M_CK440_CPU0_DN ; 2 = CLK_25M_CK440_CPU0_R_DN
R1015  Q_RES  0 5% EMPTY  pkg 0402LF  page 209 : 1 = CLK_25M_PCH_CPU0_DN ; 2 = CLK_25M_NSSC_CPU0_DN
R1016  Q_RES  0 5% CHIP  pkg 0402LF  page 209 : 1 = CLK_25M_CK440_CPU1_DP ; 2 = CLK_25M_CK440_CPU1_R_DP
R1017  Q_RES  0 5% EMPTY  pkg 0402LF  page 209 : 1 = CLK_25M_PCH_CPU1_DP ; 2 = CLK_25M_NSSC_CPU1_DP
R1018  Q_RES  0 5% CHIP  pkg 0402LF  page 209 : 1 = CLK_25M_CK440_CPU1_DN ; 2 = CLK_25M_CK440_CPU1_R_DN
R1019  Q_RES  0 5% EMPTY  pkg 0402LF  page 209 : 1 = CLK_25M_PCH_CPU1_DN ; 2 = CLK_25M_NSSC_CPU1_DN
R1020  Q_RES  0 5% CHIP  pkg 0402LF  page 209 : 1 = CLK_25M_CK440_CPU0_R_DP ; 2 = CLK_25M_NSSC_CPU0_DP
R1021  Q_RES  0 5% CHIP  pkg 0402LF  page 209 : 1 = CLK_25M_CK440_CPU0_R_DN ; 2 = CLK_25M_NSSC_CPU0_DN
R1022  Q_RES  0 5% CHIP  pkg 0402LF  page 209 : 1 = CLK_25M_CK440_CPU1_R_DP ; 2 = CLK_25M_NSSC_CPU1_DP
R1023  Q_RES  0 5% CHIP  pkg 0402LF  page 209 : 1 = CLK_25M_CK440_CPU1_R_DN ; 2 = CLK_25M_NSSC_CPU1_DN
R1024  Q_RES  100 1% CHIP  pkg 0402LF  page 182 : 1 = JTAG_DBP_TCK_PCH ; 2 = GND
R1025  Q_RES  75 1% EMPTY  pkg 0402LF  page 182 : 1 = JTAG_DBP_CPU_GTL_TCK ; 2 = GND
R1026  Q_RES  1K 1% CHIP  pkg 0402LF  page 182 : 1 = JTAG_DBP_PMODE ; 2 = P1V05_PCH_AUX
R1044  Q_RES  130 1% CHIP  pkg 0402LF  page 255 : 1 = LED_PWRGD_CPUPWRGD_GTL ; 2 = P3V3_AUX
R1089  Q_RES  2.2K 5% CHIP  pkg 0402LF  page 231 : 1 = P3V3_AUX ; 2 = SMB_SENSOR_M2_P0_3V3AUX_SCL
R1090  Q_RES  2.2K 5% CHIP  pkg 0402LF  page 231 : 1 = P3V3_AUX ; 2 = SMB_SENSOR_M2_P0_3V3AUX_SDA
R1099  Q_RES  10K 1% CHIP  pkg 0402LF  page 214 : 1 = P3V3_AUX ; 2 = PU_CLK25M_OSC_FPGA_EN
R1100  Q_RES  33.2 1% CHIP  pkg 0402LF  page 214 : 1 = CLK_25M_OSC_FPGA_R ; 2 = CLK_25M_OSC_MAIN_FPGA
R1106  Q_RES  10K 1% CHIP  pkg 0402LF  page 215 : 1 = P3V3_AUX ; 2 = FM_PLD_REV_R_N
R1117  Q_RES  6.19K 1% CHIP  pkg 0402LF  page 301 : 1 = MB0_P12V_STBY_PWRGD ; 2 = AGND_HSC
R1123  Q_RES  1K 1% EMPTY  pkg 0402LF  page 158 : 1 = P3V3_AUX ; 2 = PD_SMB_OCP1_HP_ADD2
R1124  Q_RES  1K 1% CHIP  pkg 0402LF  page 158 : 1 = PD_SMB_OCP1_HP_ADD2 ; 2 = GND
R1126  Q_RES  1K 1% CHIP  pkg 0402LF  page 158 : 1 = PD_SMB_OCP1_HP_ADD1 ; 2 = GND
R1127  Q_RES  1K 1% EMPTY  pkg 0402LF  page 158 : 1 = P3V3_AUX ; 2 = PD_SMB_OCP1_HP_ADD0
R1128  Q_RES  1K 1% CHIP  pkg 0402LF  page 158 : 1 = PD_SMB_OCP1_HP_ADD0 ; 2 = GND
R1129  Q_RES  1K 1% CHIP  pkg 0402LF  page 158 : 1 = P3V3_AUX ; 2 = HP_LVC3_OCP_V3_1_PRSNT2
R1130  Q_RES  33.2 1% CHIP  pkg 0402LF  page 158 : 1 = SMB_PEHPCPU0_LVC3_SCL ; 2 = SMB_PEHPCPU0_LVC3_R_SCL
R1131  Q_RES  33.2 1% CHIP  pkg 0402LF  page 158 : 1 = SMB_PEHPCPU0_LVC3_SDA ; 2 = SMB_PEHPCPU0_LVC3_R_SDA
R1132  Q_RES  1K 1% EMPTY  pkg 0402LF  page 164 : 1 = P3V3_AUX ; 2 = HP_OCP_V3_2_RST_R
R1138  Q_RES  10K 1% CHIP  pkg 0402LF  page 155 : 1 = P3V3_AUX ; 2 = CLK_50M_EN
R1139  Q_RES  0 5% CHIP  pkg 0402LF  page 155 : 1 = CLK_50M_RMII ; 2 = CLK_50M_RMII_R
R1140  Q_RES  27.4 1% CHIP  pkg 0402LF  page 155 : 1 = CLK_50M_BMC_MAC_R ; 2 = CLK_50M_RMII_BMC_OCP
R1141  Q_RES  27.4 1% CHIP  pkg 0402LF  page 155 : 1 = CLK_50M_NCSI_OCP_1 ; 2 = CLK_50M_NCSI_OCP_SFF
R1147  Q_RES  0 5% CHIP  pkg 0402LF  page 156 : 1 = HP_LVC3_OCP_V3_1_PRSNT2_N_R ; 2 = HP_LVC3_OCP_V3_1_ATTN_OUT_SW_N
R1148  Q_RES  0 5% CHIP  pkg 0402LF  page 156 : 1 = HP_LVC3_OCP_V3_1_PRSNT2_N_R ; 2 = HP_LVC3_OCP_V3_1_PRSNT2_N
R1149  Q_RES  10K 1% CHIP  pkg 0402LF  page 156 : 1 = P3V3_AUX ; 2 = HP_LVC3_OCP_V3_1_ATTN_OUT_SW_N
R1150  Q_RES  10K 1% CHIP  pkg 0402LF  page 156 : 1 = P3V3_AUX ; 2 = HP_LVC3_OCP_V3_1_PRSNT2_N
R1184  Q_RES  0 5% CHIP  pkg 0402LF  page 239 : 1 = JTAG_BMC_DBP_TMS_R ; 2 = JTAG_BMC_DBP_TMS
R1194  Q_RES  4.75K 1% EMPTY  pkg 0402LF  page 208 : 1 = P3V3_AUX ; 2 = FM_CK440_MXCK_25M_100M
R1195  Q_RES  130 1% CHIP  pkg 0402LF  page 218 : 1 = P3V3_AUX ; 2 = PU_PLD_HEARTBEAT_LVC3
R1196  Q_RES  4.75K 1% CHIP  pkg 0402LF  page 208 : 1 = FM_CK440_MXCK_25M_100M ; 2 = GND
R1197  Q_RES  1K 1% EMPTY  pkg 0402LF  page 182 : 1 = GND ; 2 = PD_SUSCLK
R1198  Q_RES  10K 1% CHIP  pkg 0402LF  page 182 : 1 = P3V3_AUX ; 2 = PU_ACPRESENT
R1200  Q_RES  100 1% CHIP  pkg 0402LF  page 182 : 1 = FM_PCH_TRIGGER0_N ; 2 = FM_PCH_TRIGGER0_R_N
R1201  Q_RES  49.9 1% CHIP  pkg 0402LF  page 182 : 1 = FM_PCH_TRIGGER1_N ; 2 = FM_PCH_TRIGGER1_R_N
R1202  Q_RES  20K 1% CHIP  pkg 0402LF  page 185 : 1 = P3V3_RTC_AUX ; 2 = RST_SRTCRST_N
R1203  Q_RES  1K 1% CHIP  pkg 0402LF  page 185 : 1 = P3V_BAT ; 2 = P3V_BAT_R
R1204  Q_RES  10K 1% EMPTY  pkg 0402LF  page 208 : 1 = P3V3_AUX ; 2 = PU_CK440_SHFT_LD_N
R1205  Q_RES  33.2 1% CHIP  pkg 0402LF  page 223 : 1 = RST_PLTRST_N ; 2 = RST_PLTRST_PLD_N
R1206  Q_RES  33.2 1% CHIP  pkg 0402LF  page 223 : 1 = RST_MB_STBY_R_N ; 2 = RST_MB_STBY_N
R1207  Q_RES  33.2 1% CHIP  pkg 0402LF  page 223 : 1 = RST_RSMRST_PLD_R_N ; 2 = RST_RSMRST_PCH_N
R1214  Q_RES  0 5% CHIP  pkg 0402LF  page 202 : 1 = IRQ_LPC_PIRQA_N_ESPI_ALERT0_N ; 2 = IRQ_LPC_PIRQA_N_ESPI_ALERT0_R_N
R1215  Q_RES  49.9 1% CHIP  pkg 0402LF  page 202 : 1 = IRQ_ESPI_LPC_SERIRQ_ALERT_N ; 2 = IRQ_ESPI_LPC_SERIRQ_ALERT_R_N
R1216  Q_RES  1.5K 1% CHIP  pkg 0402LF  page 80 : 1 = P3V3_AUX ; 2 = FM_S3M_CPU0_CPLD_CRC_ERROR
R1217  Q_RES  1.5K 1% CHIP  pkg 0402LF  page 80 : 1 = P3V3_AUX ; 2 = FM_S3M_CPU1_CPLD_CRC_ERROR
R1220  Q_RES  1K 1% EMPTY  pkg 0402LF  page 200 : 1 = P3V3_AUX ; 2 = FM_PCH_MCRO_LDO
R1221  Q_RES  1K 1% CHIP  pkg 0402LF  page 200 : 1 = FM_PCH_MCRO_LDO ; 2 = GND
R1226  Q_RES  10K 1% CHIP  pkg 0402LF  page 43 : 1 = PD_JTAG_CPU0_PLD_TCK ; 2 = GND
R1227  Q_RES  10K 1% CHIP  pkg 0402LF  page 43 : 1 = PD_JTAG_CPU1_PLD_TCK ; 2 = GND
R1229  Q_RES  240 1% EMPTY  pkg 0402LF  page 119 : 1 = PVNN_TERM_CPU1 ; 2 = PUD_XTAL_CPU1_MODE0
R1230  Q_RES  240 1% EMPTY  pkg 0402LF  page 119 : 1 = PVNN_TERM_CPU1 ; 2 = PUD_XTAL_CPU1_MODE1
R1232  Q_RES  240 1% EMPTY  pkg 0402LF  page 119 : 1 = PVNN_TERM_CPU0 ; 2 = PUD_XTAL_CPU0_MODE0
R1233  Q_RES  240 1% EMPTY  pkg 0402LF  page 119 : 1 = PVNN_TERM_CPU0 ; 2 = PUD_XTAL_CPU0_MODE1
R1235  Q_RES  240 1% EMPTY  pkg 0402LF  page 119 : 1 = GND ; 2 = PUD_XTAL_CPU1_MODE0
R1236  Q_RES  240 1% EMPTY  pkg 0402LF  page 119 : 1 = GND ; 2 = PUD_XTAL_CPU1_MODE1
R1237  Q_RES  240 1% EMPTY  pkg 0402LF  page 119 : 1 = GND ; 2 = PD_EXT_CLK_SEL_CPU0
R1238  Q_RES  240 1% EMPTY  pkg 0402LF  page 119 : 1 = GND ; 2 = PUD_XTAL_CPU0_MODE0
R1239  Q_RES  240 1% EMPTY  pkg 0402LF  page 119 : 1 = GND ; 2 = PUD_XTAL_CPU0_MODE1
R1240  Q_RES  0 5% CHIP  pkg 0402LF  page 117 : 1 = H_CPU0_PM_FAST_WAKE_N ; 2 = H_CPU_PM_FAST_WAKE_N
R1241  Q_RES  249 1% CHIP  pkg 0402LF  page 117 : 1 = H_PMAX_TRIGGER_IO_CPU0 ; 2 = GND
R1242  Q_RES  301 1% CHIP  pkg 0402LF  page 117 : 1 = PVNN_TERM_CPU0 ; 2 = H_CPU_PM_FAST_WAKE_N
R1243  Q_RES  249 1% CHIP  pkg 0402LF  page 117 : 1 = H_PMAX_TRIGGER_IO_CPU1 ; 2 = GND
R1244  Q_RES  301 1% CHIP  pkg 0402LF  page 117 : 1 = PVNN_TERM_CPU1 ; 2 = H_CPU_PM_FAST_WAKE_N
R1247  Q_RES  0 5% CHIP  pkg 0402LF  page 203 : 1 = FM_PCH_CPU_PWR_DEBUG_N ; 2 = FM_CPU_FBRK_DEBUG_N
R1249  Q_RES  0 5% CHIP  pkg 0402LF  page 203 : 1 = FM_THERMTRIP_DLY_LVC1_N ; 2 = H_THERMTRIP_LVC1_N
R1253  Q_RES  1K 1% CHIP  pkg 0402LF  page 204 : 1 = PGPPA_AUX ; 2 = IRQ_LPC_PIRQA_N_ESPI_ALERT0_N
R1254  Q_RES  10K 1% CHIP  pkg 0402LF  page 204 : 1 = PGPPA_AUX ; 2 = IRQ_LPC_SERIRQ_ESPI_CS1_N
R1255  Q_RES  1K 1% CHIP  pkg 0402LF  page 204 : 1 = PGPPA_AUX ; 2 = ESPI_ALERT1_N_LPC_RCIN_N
R1257  Q_RES  10K 1% CHIP  pkg 0402LF  page 204 : 1 = P3V3_AUX ; 2 = PU_PCH_VRALERT_N
R1259  Q_RES  10K 1% CHIP  pkg 0402LF  page 204 : 1 = P3V3_AUX ; 2 = PU_LPC_PME_N
R1260  Q_RES  10K 1% EMPTY  pkg 0402LF  page 204 : 1 = P1V05_PCH_AUX ; 2 = H_CPU_ERR0_PCH_R_N
R1262  Q_RES  10K 1% EMPTY  pkg 0402LF  page 204 : 1 = P1V05_PCH_AUX ; 2 = H_CPU_ERR2_PCH_R_N
R1263  Q_RES  33.2 1% CHIP  pkg 0402LF  page 203 : 1 = FM_PLT_BMC_THERMTRIP_R_N ; 2 = FM_PCH_BMC_THERMTRIP_N
R1266  Q_RES  75 1% CHIP  pkg 0402LF  page 203 : 1 = P1V05_PCH_AUX ; 2 = H_THERMTRIP_LVC1_N
R1267  Q_RES  1K 1% CHIP  pkg 0402LF  page 208 : 1 = PU_CK440_SHFT_LD_N ; 2 = GND
R1268  Q_RES  33.2 1% CHIP  pkg 0402LF  page 183 : 1 = IRQ_BMC_PCH_NMI_R ; 2 = IRQ_BMC_PCH_NMI
R1269  Q_RES  4.75K 1% CHIP  pkg 0402LF  page 183 : 1 = IRQ_BMC_PCH_NMI ; 2 = GND
R1270  Q_RES  240 1% EMPTY  pkg 0402LF  page 44 : 1 = PD_CPU1_PROCDIS_COD_GTL_N ; 2 = GND
R1271  Q_RES  2.21K 1% EMPTY  pkg 0402LF  page 194 : 1 = P3V3_AUX ; 2 = FM_PCH_SATA_RAID_KEY
R1273  Q_RES  22 1% CHIP  pkg 0402LF  page 209 : 1 = CLK_100M_OCP_SFF_2_R_DP ; 2 = CLK_100M_OCP_SFF_2_DP
R1274  Q_RES  22 1% CHIP  pkg 0402LF  page 209 : 1 = CLK_100M_OCP_SFF_2_R_DN ; 2 = CLK_100M_OCP_SFF_2_DN
R1275  Q_RES  22 1% CHIP  pkg 0402LF  page 209 : 1 = CLK_100M_OCP_SFF_3_R_DP ; 2 = CLK_100M_OCP_SFF_3_DP
R1276  Q_RES  22 1% CHIP  pkg 0402LF  page 209 : 1 = CLK_100M_OCP_SFF_3_R_DN ; 2 = CLK_100M_OCP_SFF_3_DN
R1289  Q_RES  100K 1% CHIP  pkg 0402LF  page 154 : 1 = FB_BMC_ISOLATE ; 2 = GND
R1290  Q_RES  22 1% EMPTY  pkg 0402LF  page 154 : 1 = OCP_SFF_RBT_ARB_IN_R ; 2 = OCP_SFF_RBT_ARB_IN
R1291  Q_RES  22 1% CHIP  pkg 0402LF  page 154 : 1 = NCSI_BMC_CRS_DV_R ; 2 = RMII_OCP_BMC_CRSDV
R1292  Q_RES  22 1% CHIP  pkg 0402LF  page 154 : 1 = NCSI_BMC_RXD0_R ; 2 = RMII_OCP_BMC_RXD_0
R1293  Q_RES  22 1% CHIP  pkg 0402LF  page 154 : 1 = NCSI_BMC_RXD1_R ; 2 = RMII_OCP_BMC_RXD_1
R1294  Q_RES  0 5% CHIP  pkg 0402LF  page 154 : 1 = NCSI_BMC_TX_EN_R ; 2 = RMII_BMC_OCP_TX_EN
R1295  Q_RES  0 5% CHIP  pkg 0402LF  page 154 : 1 = NCSI_BMC_TXD0_R ; 2 = RMII_BMC_OCP_TXD_0
R1296  Q_RES  0 5% CHIP  pkg 0402LF  page 154 : 1 = NCSI_BMC_TXD1_R ; 2 = RMII_BMC_OCP_TXD_1
